#ISCELL
  mstr_misc dns *
  *
#ISCELL
  pure_quanta quanta_title_block_c *
  *
#ISCELL
  standard offpage *
  page331_i1
#ISCELL
  pure_quanta_power universal_power *
  page331_i10
#ISCELL
  pure_quanta_power universal_gnd *
  page331_i100
#ISCELL
  pure_quanta_power universal_gnd *
  page331_i101
#ISCELL
  pure_quanta_power universal_gnd *
  page331_i102
#CELL
  pure_quanta q_res *
  page331_i107
#CELL
  pure_quanta q_res *
  page331_i108
#CELL
  pure_quanta q_res *
  page331_i109
#ISCELL
  pure_quanta_power universal_gnd *
  page331_i11
#CELL
  pure_quanta q_res *
  page331_i110
#CELL
  pure_quanta q_cap *
  page331_i111
#ISCELL
  standard offpage *
  page331_i12
#CELL
  pure_quanta q_res *
  page331_i13
#CELL
  pure_quanta q_res *
  page331_i14
#ISCELL
  pure_quanta_power universal_power *
  page331_i15
#ISCELL
  pure_quanta_power universal_gnd *
  page331_i16
#CELL
  pure_quanta mosfet_nch_dual *
  page331_i17
#CELL
  pure_quanta q_res *
  page331_i18
#ISCELL
  pure_quanta_power universal_power *
  page331_i19
#CELL
  pure_quanta q_res *
  page331_i2
#ISCELL
  pure_quanta_power universal_gnd *
  page331_i20
#CELL
  pure_quanta mosfet_nch_dual *
  page331_i21
#CELL
  pure_quanta mosfet_nch_dual *
  page331_i22
#CELL
  pure_quanta q_res *
  page331_i23
#ISCELL
  pure_quanta_power universal_power *
  page331_i24
#CELL
  pure_quanta mosfet_nch_dual *
  page331_i25
#ISCELL
  pure_quanta_power universal_gnd *
  page331_i26
#CELL
  pure_quanta q_res *
  page331_i27
#CELL
  pure_quanta mosfet_nch_dual *
  page331_i28
#CELL
  pure_quanta mosfet_nch_dual *
  page331_i29
#ISCELL
  pure_quanta_power universal_gnd *
  page331_i3
#ISCELL
  pure_quanta_power universal_power *
  page331_i30
#ISCELL
  pure_quanta_power universal_gnd *
  page331_i31
#ISCELL
  pure_quanta_power universal_gnd *
  page331_i32
#CELL
  pure_quanta q_cap *
  page331_i33
#ISCELL
  pure_quanta_power universal_gnd *
  page331_i34
#CELL
  pure_quanta q_res *
  page331_i35
#ISCELL
  pure_quanta_power universal_power *
  page331_i36
#ISCELL
  pure_quanta_power universal_gnd *
  page331_i37
#ISCELL
  standard offpage *
  page331_i38
#CELL
  pure_quanta q_res *
  page331_i39
#CELL
  pure_quanta q_res *
  page331_i4
#ISCELL
  pure_quanta_power universal_power *
  page331_i40
#ISCELL
  pure_quanta_power universal_gnd *
  page331_i41
#CELL
  pure_quanta q_cap *
  page331_i42
#ISCELL
  pure_quanta_power universal_gnd *
  page331_i43
#CELL
  pure_quanta q_cap *
  page331_i44
#ISCELL
  standard offpage *
  page331_i45
#ISCELL
  standard offpage *
  page331_i46
#CELL
  pure_quanta q_res *
  page331_i47
#ISCELL
  pure_quanta_power universal_power *
  page331_i48
#ISCELL
  pure_quanta_power universal_power *
  page331_i49
#ISCELL
  standard offpage *
  page331_i5
#ISCELL
  standard offpage *
  page331_i51
#ISCELL
  pure_quanta_power universal_gnd *
  page331_i53
#ISCELL
  pure_quanta_power universal_gnd *
  page331_i54
#CELL
  pure_quanta mosfet_nch_dual *
  page331_i55
#ISCELL
  pure_quanta_power universal_power *
  page331_i56
#CELL
  pure_quanta q_res *
  page331_i57
#ISCELL
  pure_quanta_power universal_power *
  page331_i58
#ISCELL
  pure_quanta_power universal_power *
  page331_i6
#ISCELL
  pure_quanta_power universal_gnd *
  page331_i60
#CELL
  pure_quanta mosfet_nch_dual *
  page331_i61
#CELL
  pure_quanta q_res *
  page331_i62
#ISCELL
  pure_quanta_power universal_gnd *
  page331_i63
#ISCELL
  standard offpage *
  page331_i64
#ISCELL
  pure_quanta_power universal_gnd *
  page331_i7
#CELL
  pure_quanta q_res *
  page331_i8
#CELL
  pure_quanta q_res *
  page331_i85
#CELL
  pure_quanta 74lvc2g17gw *
  page331_i86
#CELL
  pure_quanta q_res *
  page331_i87
#ISCELL
  pure_quanta_power universal_power *
  page331_i88
#CELL
  pure_quanta q_res *
  page331_i89
#CELL
  pure_quanta q_res *
  page331_i9
#ISCELL
  pure_quanta_power universal_gnd *
  page331_i90
#ISCELL
  standard offpage *
  page331_i91
#ISCELL
  pure_quanta_power universal_gnd *
  page331_i92
#CELL
  pure_quanta q_cap *
  page331_i93
#ISCELL
  pure_quanta_power universal_power *
  page331_i94
#ISCELL
  standard offpage *
  page331_i95
#ISCELL
  pure_quanta_power universal_power *
  page331_i96
#CELL
  pure_quanta q_res *
  page331_i97
#CELL
  pure_quanta q_res *
  page331_i98
#CELL
  pure_quanta q_res *
  page331_i99
